# BASEBOARD_FAB2 (Tioga Pass) — schematic netlist excerpt (pin names and nets, part order shuffled) for the footprints in the layout excerpt that follows; sources: Cadence DE-HDL packaged netlist, KiCad conversion of Wiwynn_Tioga_Pass_MB.brd

R8E28  RES  0.0 5% CHIP  pkg 0402  page 142 : A = FM_PE_SLOTX24_WAKE_N ; B = FM_ALL_WAKE_N
R1R17  RES  2.21K 1% CHIP  pkg 0402  page 188 : A = P3V3_STBY ; B = SMB_PCH_MEZZ_LOM2_SDA
R7P19  RES  100.0 1% CHIP  pkg 0402  page 55 : A = A_CPU1_GHJ_RCOMP2 ; B = GND

(kicad_pcb
	(version 20260206)
	(generator "pcbnew")
	(generator_version "10.0")
	(general
		(thickness 1.6)
		(legacy_teardrops no)
	)
	(paper "A4")
	(title_block
		(title "Wiwynn_Tioga_Pass_MB.brd")
		(comment 1 "Tioga Pass / footprints 4580-4582 of 4770")
	)
	(layers
		(0 "F.Cu" signal "TOP")
		(4 "In1.Cu" signal "L2GND")
		(6 "In2.Cu" signal "L3")
		(8 "In3.Cu" signal "L4GND")
		(10 "In4.Cu" signal "L5")
		(12 "In5.Cu" signal "L6GND")
		(14 "In6.Cu" signal "L7VCC")
		(16 "In7.Cu" signal "L8VCC")
		(18 "In8.Cu" signal "L9GND")
		(20 "In9.Cu" signal "L10")
		(22 "In10.Cu" signal "L11GND")
		(24 "In11.Cu" signal "L12")
		(26 "In12.Cu" signal "L13GND")
		(2 "B.Cu" signal "BOTTOM")
		(9 "F.Adhes" user "F.Adhesive")
		(11 "B.Adhes" user "B.Adhesive")
		(13 "F.Paste" user "Package Geometry/Pastemask Top")
		(15 "B.Paste" user "Package Geometry/Pastemask Bottom")
		(5 "F.SilkS" user "Ref Des/Silkscreen Top")
		(7 "B.SilkS" user "Ref Des/Silkscreen Bottom")
		(1 "F.Mask" user "Board Geometry/Soldermask Top")
		(3 "B.Mask" user "Board Geometry/Soldermask Bottom")
		(17 "Dwgs.User" user "User.Drawings")
		(19 "Cmts.User" user "User.Comments")
		(21 "Eco1.User" user "User.Eco1")
		(23 "Eco2.User" user "User.Eco2")
		(25 "Edge.Cuts" user "Board Geometry/Outline")
		(27 "Margin" user)
		(31 "F.CrtYd" user "Package Geometry/Place Bound Top")
		(29 "B.CrtYd" user "Package Geometry/Place Bound Bottom")
		(35 "F.Fab" user "Ref Des/Assembly Top")
		(33 "B.Fab" user "Ref Des/Assembly Bottom")
	)
	(footprint ""
		(layer "B.Cu")
		(at 117.1956 -71.882 -90)
		(property "Reference" "R7P19"
			(at 0 0 90)
			(layer "B.SilkS")
			(hide yes)
			(effects
				(font
					(size 1.27 1.27)
				)
				(justify mirror)
			)
		)
		(property "Value" ""
			(at 0 0 90)
			(layer "B.Fab")
			(effects
				(font
					(size 1.27 1.27)
				)
				(justify mirror)
			)
		)
		(duplicate_pad_numbers_are_jumpers no)
		(fp_poly
			(pts
				(xy 0.2794 -0.1016) (xy -0.2794 -0.1016) (xy -0.2794 0.9906) (xy 0.2794 0.9906)
			)
			(stroke
				(width 0)
				(type default)
			)
			(fill no)
			(layer "B.CrtYd")
		)
		(fp_line
			(start -0.2794 0.9906)
			(end -0.2794 -0.1016)
			(stroke
				(width 0.1)
				(type default)
			)
			(layer "B.Fab")
		)
		(fp_line
			(start 0.2794 0.9906)
			(end -0.2794 0.9906)
			(stroke
				(width 0.1)
				(type default)
			)
			(layer "B.Fab")
		)
		(fp_line
			(start -0.2794 -0.1016)
			(end 0.2794 -0.1016)
			(stroke
				(width 0.1)
				(type default)
			)
			(layer "B.Fab")
		)
		(fp_line
			(start 0.2794 -0.1016)
			(end 0.2794 0.9906)
			(stroke
				(width 0.1)
				(type default)
			)
			(layer "B.Fab")
		)
		(pad "1" smd rect
			(at 0 0 90)
			(size 0.508 0.508)
			(layers "B.Cu" "B.Mask" "B.Paste")
			(net "A_CPU1_GHJ_RCOMP2")
		)
		(pad "2" smd rect
			(at 0 0.889 90)
			(size 0.508 0.508)
			(layers "B.Cu" "B.Mask" "B.Paste")
			(net "GND")
		)
		(zone
			(layer "B.Cu")
			(hatch none 0.5)
			(connect_pads
				(clearance 0)
			)
			(min_thickness 0.25)
			(keepout
				(tracks not_allowed)
				(vias allowed)
				(pads allowed)
				(copperpour not_allowed)
				(footprints allowed)
			)
			(placement
				(enabled no)
				(sheetname "")
			)
			(fill
				(thermal_gap 0.5)
				(thermal_bridge_width 0.5)
				(island_removal_mode 0)
			)
			(polygon
				(pts
					(xy 116.5606 -71.628) (xy 116.5606 -72.136) (xy 116.9416 -72.136) (xy 116.9416 -71.628)
				)
			)
		)
		(zone
			(layer "B.Cu")
			(hatch none 0.5)
			(connect_pads
				(clearance 0)
			)
			(min_thickness 0.25)
			(keepout
				(tracks allowed)
				(vias not_allowed)
				(pads allowed)
				(copperpour not_allowed)
				(footprints allowed)
			)
			(placement
				(enabled no)
				(sheetname "")
			)
			(fill
				(thermal_gap 0.5)
				(thermal_bridge_width 0.5)
				(island_removal_mode 0)
			)
			(polygon
				(pts
					(xy 116.9416 -71.628) (xy 116.9416 -72.136) (xy 116.5606 -72.136) (xy 116.5606 -71.628)
				)
			)
		)
	)
	(footprint ""
		(layer "B.Cu")
		(at 482.65969 -58.069988 -90)
		(property "Reference" "R8E28"
			(at 0 0 90)
			(layer "B.SilkS")
			(hide yes)
			(effects
				(font
					(size 1.27 1.27)
				)
				(justify mirror)
			)
		)
		(property "Value" ""
			(at 0 0 90)
			(layer "B.Fab")
			(effects
				(font
					(size 1.27 1.27)
				)
				(justify mirror)
			)
		)
		(duplicate_pad_numbers_are_jumpers no)
		(fp_poly
			(pts
				(xy 0.2794 -0.1016) (xy -0.2794 -0.1016) (xy -0.2794 0.9906) (xy 0.2794 0.9906)
			)
			(stroke
				(width 0)
				(type default)
			)
			(fill no)
			(layer "B.CrtYd")
		)
		(fp_line
			(start -0.2794 0.9906)
			(end -0.2794 -0.1016)
			(stroke
				(width 0.1)
				(type default)
			)
			(layer "B.Fab")
		)
		(fp_line
			(start 0.2794 0.9906)
			(end -0.2794 0.9906)
			(stroke
				(width 0.1)
				(type default)
			)
			(layer "B.Fab")
		)
		(fp_line
			(start -0.2794 -0.1016)
			(end 0.2794 -0.1016)
			(stroke
				(width 0.1)
				(type default)
			)
			(layer "B.Fab")
		)
		(fp_line
			(start 0.2794 -0.1016)
			(end 0.2794 0.9906)
			(stroke
				(width 0.1)
				(type default)
			)
			(layer "B.Fab")
		)
		(pad "1" smd rect
			(at 0 0 90)
			(size 0.508 0.508)
			(layers "B.Cu" "B.Mask" "B.Paste")
			(net "FM_PE_SLOTX24_WAKE_N")
		)
		(pad "2" smd rect
			(at 0 0.889 90)
			(size 0.508 0.508)
			(layers "B.Cu" "B.Mask" "B.Paste")
			(net "FM_ALL_WAKE_N")
		)
		(zone
			(layer "B.Cu")
			(hatch none 0.5)
			(connect_pads
				(clearance 0)
			)
			(min_thickness 0.25)
			(keepout
				(tracks not_allowed)
				(vias allowed)
				(pads allowed)
				(copperpour not_allowed)
				(footprints allowed)
			)
			(placement
				(enabled no)
				(sheetname "")
			)
			(fill
				(thermal_gap 0.5)
				(thermal_bridge_width 0.5)
				(island_removal_mode 0)
			)
			(polygon
				(pts
					(xy 482.02469 -57.815988) (xy 482.02469 -58.323988) (xy 482.40569 -58.323988) (xy 482.40569 -57.815988)
				)
			)
		)
		(zone
			(layer "B.Cu")
			(hatch none 0.5)
			(connect_pads
				(clearance 0)
			)
			(min_thickness 0.25)
			(keepout
				(tracks allowed)
				(vias not_allowed)
				(pads allowed)
				(copperpour not_allowed)
				(footprints allowed)
			)
			(placement
				(enabled no)
				(sheetname "")
			)
			(fill
				(thermal_gap 0.5)
				(thermal_bridge_width 0.5)
				(island_removal_mode 0)
			)
			(polygon
				(pts
					(xy 482.40569 -57.815988) (xy 482.40569 -58.323988) (xy 482.02469 -58.323988) (xy 482.02469 -57.815988)
				)
			)
		)
	)
	(footprint ""
		(layer "B.Cu")
		(at 470.027 -61.722 -90)
		(property "Reference" "R1R17"
			(at 0 0 90)
			(layer "B.SilkS")
			(hide yes)
			(effects
				(font
					(size 1.27 1.27)
				)
				(justify mirror)
			)
		)
		(property "Value" ""
			(at 0 0 90)
			(layer "B.Fab")
			(effects
				(font
					(size 1.27 1.27)
				)
				(justify mirror)
			)
		)
		(duplicate_pad_numbers_are_jumpers no)
		(fp_poly
			(pts
				(xy 0.2794 -0.1016) (xy -0.2794 -0.1016) (xy -0.2794 0.9906) (xy 0.2794 0.9906)
			)
			(stroke
				(width 0)
				(type default)
			)
			(fill no)
			(layer "B.CrtYd")
		)
		(fp_line
			(start -0.2794 0.9906)
			(end -0.2794 -0.1016)
			(stroke
				(width 0.1)
				(type default)
			)
			(layer "B.Fab")
		)
		(fp_line
			(start 0.2794 0.9906)
			(end -0.2794 0.9906)
			(stroke
				(width 0.1)
				(type default)
			)
			(layer "B.Fab")
		)
		(fp_line
			(start -0.2794 -0.1016)
			(end 0.2794 -0.1016)
			(stroke
				(width 0.1)
				(type default)
			)
			(layer "B.Fab")
		)
		(fp_line
			(start 0.2794 -0.1016)
			(end 0.2794 0.9906)
			(stroke
				(width 0.1)
				(type default)
			)
			(layer "B.Fab")
		)
		(pad "1" smd rect
			(at 0 0 90)
			(size 0.508 0.508)
			(layers "B.Cu" "B.Mask" "B.Paste")
			(net "P3V3_STBY")
		)
		(pad "2" smd rect
			(at 0 0.889 90)
			(size 0.508 0.508)
			(layers "B.Cu" "B.Mask" "B.Paste")
			(net "SMB_PCH_MEZZ_LOM2_SDA")
		)
		(zone
			(layer "B.Cu")
			(hatch none 0.5)
			(connect_pads
				(clearance 0)
			)
			(min_thickness 0.25)
			(keepout
				(tracks not_allowed)
				(vias allowed)
				(pads allowed)
				(copperpour not_allowed)
				(footprints allowed)
			)
			(placement
				(enabled no)
				(sheetname "")
			)
			(fill
				(thermal_gap 0.5)
				(thermal_bridge_width 0.5)
				(island_removal_mode 0)
			)
			(polygon
				(pts
					(xy 469.392 -61.468) (xy 469.392 -61.976) (xy 469.773 -61.976) (xy 469.773 -61.468)
				)
			)
		)
		(zone
			(layer "B.Cu")
			(hatch none 0.5)
			(connect_pads
				(clearance 0)
			)
			(min_thickness 0.25)
			(keepout
				(tracks allowed)
				(vias not_allowed)
				(pads allowed)
				(copperpour not_allowed)
				(footprints allowed)
			)
			(placement
				(enabled no)
				(sheetname "")
			)
			(fill
				(thermal_gap 0.5)
				(thermal_bridge_width 0.5)
				(island_removal_mode 0)
			)
			(polygon
				(pts
					(xy 469.773 -61.468) (xy 469.773 -61.976) (xy 469.392 -61.976) (xy 469.392 -61.468)
				)
			)
		)
	)
)
